1 2 3 4 5 6 7 8 9 10 11 12 13 14
1413121110987654321
DRAWING NO.
SCALE DWG
DO NOT 
MODEL NAME
APPD
CKD
DSN
DRN
SHEET
SIGNDESCRIPTION DATE
Wiwynn Corporation
A
B
C
D
E
G
F
H
I
J
A
B
C
D
E
F
G
H
I
J
MATERIAL
FINISH
OF
DIM IN  mm
REV
(NPTH)2.41
(NPTH)2.55
(NO TRACE AT ALL LAYERS EXCEPT GND)6.00
(PTH)4.00
(PTH)4.00
41.84
0.00
34.85
30.53
0.00
73.03
25.00
0.00
120.00
103.00
2-179.40
2-204.40
155.50
92.50
170.00
120.00 120.00 120.00
2-22.90
2-78.55
18.00
60.55
40.05
105.05 105.05
18.00
80.00
12.50
3-188.00
194.00
10.00 8.00
2-21.25
2-51.25
150.00
(NO TRACE AT ALL LAYERS EXCEPT GND)7.50
(PAD)(NO TRACE AT ALL LAYERS)9.50
(PTH)4.20
2-124.16
0.00
4.80
3.20
(NPTH)3.20
41.45
6.80
3.40
(NPTH)3.40
22.80
(NPTH)3.30
(NPTH)3.30
78.50
235.00
154.00
188.00
3-222.50
215.00
160.00
154.00
11- (PAD)(NO TRACE AT ALL LAYERS)9.50
(PAD)(NO TRACE AT ALL LAYERS)9.50
103.70
144.30
149.30
78.00
11- (PTH)3.50
(PAD)(NO TRACE AT ALL LAYERS)9.50
(PAD)(NO TRACE AT ALL LAYERS)9.50
(PAD)(NO TRACE AT ALL LAYERS)9.50(PAD)6.50
(PAD)6.50
BryceCanyon
CD 
Jess Wang 7/31
2017
Jess Wang 7/31
2017
Bryce Canyon IOM (M.2 only)
TU863+VLP / NPG171+VLP T=1.6mm 
1 1 Lenny Kao
Lenny Kao 
7/31
2017
7/31
2017
COMPONENT SIDE SOLDER SIDE
SEE DETAIL B
16342-2 VERSION B 2017-07-31
16342-2 VERSION A 2017-07-31
SEE DETAIL A
SMT NUT(087.71242.0465)
SEE DETAIL  B
SEE DETAIL  A
DETAIL  B
SCALE  3.000
DETAIL  A
SCALE  3.000